# T6G (Grand Teton) — schematic netlist excerpt (pin names and nets, part order shuffled) for the footprints in the layout excerpt that follows; sources: Cadence DE-HDL packaged netlist, KiCad conversion of 04192023_DAF0TMB3IC0_F0TG_MB_C_brd_V02_OCP.brd

R469  Q_RES  33 5% CHIP  pkg 0402LF  page 29 : A = ESPI_CPU0_D1 ; B = ESPI_CPU0_R_D1
R1815  Q_RES  0 5% CHIP  pkg 0402LF  page 150 : A = SCM_SYS_PWRBTN_N ; B = SCM_SYS_PWRBTN_R_N

(kicad_pcb
	(version 20260206)
	(generator "pcbnew")
	(generator_version "10.0")
	(general
		(thickness 1.6)
		(legacy_teardrops no)
	)
	(paper "A4")
	(title_block
		(title "04192023_DAF0TMB3IC0_F0TG_MB_C_brd_V02_OCP.brd")
		(comment 1 "Grand Teton / footprints 6756-6757 of 8354")
	)
	(layers
		(0 "F.Cu" signal "TOP")
		(4 "In1.Cu" signal "GND")
		(6 "In2.Cu" signal "IN1")
		(8 "In3.Cu" signal "GND1")
		(10 "In4.Cu" signal "IN2")
		(12 "In5.Cu" signal "GND2")
		(14 "In6.Cu" signal "IN3")
		(16 "In7.Cu" signal "GND3")
		(18 "In8.Cu" signal "VCC")
		(20 "In9.Cu" signal "VCC1")
		(22 "In10.Cu" signal "GND4")
		(24 "In11.Cu" signal "IN4")
		(26 "In12.Cu" signal "GND5")
		(28 "In13.Cu" signal "IN5")
		(30 "In14.Cu" signal "GND6")
		(32 "In15.Cu" signal "IN6")
		(34 "In16.Cu" signal "GND7")
		(2 "B.Cu" signal "BOTTOM")
		(9 "F.Adhes" user "F.Adhesive")
		(11 "B.Adhes" user "B.Adhesive")
		(13 "F.Paste" user "Package Geometry/Pastemask Top")
		(15 "B.Paste" user "Package Geometry/Pastemask Bottom")
		(5 "F.SilkS" user "Ref Des/Silkscreen Top")
		(7 "B.SilkS" user "Ref Des/Silkscreen Bottom")
		(1 "F.Mask" user "Board Geometry/Soldermask Top")
		(3 "B.Mask" user "Board Geometry/Soldermask Bottom")
		(17 "Dwgs.User" user "User.Drawings")
		(19 "Cmts.User" user "User.Comments")
		(21 "Eco1.User" user "User.Eco1")
		(23 "Eco2.User" user "User.Eco2")
		(25 "Edge.Cuts" user "Board Geometry/Outline")
		(27 "Margin" user)
		(31 "F.CrtYd" user "Package Geometry/Place Bound Top")
		(29 "B.CrtYd" user "Package Geometry/Place Bound Bottom")
		(35 "F.Fab" user "Ref Des/Assembly Top")
		(33 "B.Fab" user "Ref Des/Assembly Bottom")
	)
	(footprint ""
		(layer "B.Cu")
		(at 389.731758 -321.179952)
		(property "Reference" "R469"
			(at 0 0 0)
			(layer "B.SilkS")
			(hide yes)
			(effects
				(font
					(size 1.27 1.27)
				)
				(justify mirror)
			)
		)
		(property "Value" ""
			(at 0 0 0)
			(layer "B.Fab")
			(effects
				(font
					(size 1.27 1.27)
				)
				(justify mirror)
			)
		)
		(duplicate_pad_numbers_are_jumpers no)
		(fp_line
			(start -0.7874 -0.4064)
			(end -0.7874 0.4064)
			(stroke
				(width 0.1524)
				(type default)
			)
			(layer "B.SilkS")
		)
		(fp_line
			(start -0.7874 0.4064)
			(end 0.7874 0.4064)
			(stroke
				(width 0.1524)
				(type default)
			)
			(layer "B.SilkS")
		)
		(fp_line
			(start 0.7874 -0.4064)
			(end -0.7874 -0.4064)
			(stroke
				(width 0.1524)
				(type default)
			)
			(layer "B.SilkS")
		)
		(fp_line
			(start 0.7874 0.4064)
			(end 0.7874 -0.4064)
			(stroke
				(width 0.1524)
				(type default)
			)
			(layer "B.SilkS")
		)
		(fp_line
			(start -0.67945 -0.3048)
			(end -0.67945 0.3048)
			(stroke
				(width 0.1)
				(type default)
			)
			(layer "B.Fab")
		)
		(fp_line
			(start -0.67945 0.3048)
			(end -0.120396 0.3048)
			(stroke
				(width 0.1)
				(type default)
			)
			(layer "B.Fab")
		)
		(fp_line
			(start -0.12065 -0.3048)
			(end -0.67945 -0.3048)
			(stroke
				(width 0.1)
				(type default)
			)
			(layer "B.Fab")
		)
		(fp_line
			(start -0.12065 -0.2794)
			(end -0.12065 -0.3048)
			(stroke
				(width 0.1)
				(type default)
			)
			(layer "B.Fab")
		)
		(fp_line
			(start -0.120396 0.2794)
			(end 0.12065 0.2794)
			(stroke
				(width 0.1)
				(type default)
			)
			(layer "B.Fab")
		)
		(fp_line
			(start -0.120396 0.3048)
			(end -0.120396 0.2794)
			(stroke
				(width 0.1)
				(type default)
			)
			(layer "B.Fab")
		)
		(fp_line
			(start 0.12065 -0.305054)
			(end 0.12065 -0.2794)
			(stroke
				(width 0.1)
				(type default)
			)
			(layer "B.Fab")
		)
		(fp_line
			(start 0.12065 -0.2794)
			(end -0.12065 -0.2794)
			(stroke
				(width 0.1)
				(type default)
			)
			(layer "B.Fab")
		)
		(fp_line
			(start 0.12065 0.2794)
			(end 0.12065 0.3048)
			(stroke
				(width 0.1)
				(type default)
			)
			(layer "B.Fab")
		)
		(fp_line
			(start 0.12065 0.3048)
			(end 0.67945 0.3048)
			(stroke
				(width 0.1)
				(type default)
			)
			(layer "B.Fab")
		)
		(fp_line
			(start 0.67945 -0.305054)
			(end 0.12065 -0.305054)
			(stroke
				(width 0.1)
				(type default)
			)
			(layer "B.Fab")
		)
		(fp_line
			(start 0.67945 0.3048)
			(end 0.67945 -0.305054)
			(stroke
				(width 0.1)
				(type default)
			)
			(layer "B.Fab")
		)
		(pad "1" smd circle
			(at 0.40005 0 180)
			(size 0 0)
			(layers "B.Cu" "B.Mask" "B.Paste")
			(net "ESPI_CPU0_D1")
		)
		(pad "2" smd circle
			(at -0.40005 0 180)
			(size 0 0)
			(layers "B.Cu" "B.Mask" "B.Paste")
			(net "ESPI_CPU0_R_D1")
		)
	)
	(footprint ""
		(layer "B.Cu")
		(at 143.3068 -13.762228 90)
		(property "Reference" "R1815"
			(at 0 0 90)
			(layer "B.SilkS")
			(hide yes)
			(effects
				(font
					(size 1.27 1.27)
				)
				(justify mirror)
			)
		)
		(property "Value" ""
			(at 0 0 90)
			(layer "B.Fab")
			(effects
				(font
					(size 1.27 1.27)
				)
				(justify mirror)
			)
		)
		(duplicate_pad_numbers_are_jumpers no)
		(fp_line
			(start 0.7874 -0.4064)
			(end -0.7874 -0.4064)
			(stroke
				(width 0.1524)
				(type default)
			)
			(layer "B.SilkS")
		)
		(fp_line
			(start -0.7874 -0.4064)
			(end -0.7874 0.4064)
			(stroke
				(width 0.1524)
				(type default)
			)
			(layer "B.SilkS")
		)
		(fp_line
			(start 0.7874 0.4064)
			(end 0.7874 -0.4064)
			(stroke
				(width 0.1524)
				(type default)
			)
			(layer "B.SilkS")
		)
		(fp_line
			(start -0.7874 0.4064)
			(end 0.7874 0.4064)
			(stroke
				(width 0.1524)
				(type default)
			)
			(layer "B.SilkS")
		)
		(fp_line
			(start 0.67945 -0.305054)
			(end 0.12065 -0.305054)
			(stroke
				(width 0.1)
				(type default)
			)
			(layer "B.Fab")
		)
		(fp_line
			(start 0.12065 -0.305054)
			(end 0.12065 -0.2794)
			(stroke
				(width 0.1)
				(type default)
			)
			(layer "B.Fab")
		)
		(fp_line
			(start -0.12065 -0.3048)
			(end -0.67945 -0.3048)
			(stroke
				(width 0.1)
				(type default)
			)
			(layer "B.Fab")
		)
		(fp_line
			(start -0.67945 -0.3048)
			(end -0.67945 0.3048)
			(stroke
				(width 0.1)
				(type default)
			)
			(layer "B.Fab")
		)
		(fp_line
			(start 0.12065 -0.2794)
			(end -0.12065 -0.2794)
			(stroke
				(width 0.1)
				(type default)
			)
			(layer "B.Fab")
		)
		(fp_line
			(start -0.12065 -0.2794)
			(end -0.12065 -0.3048)
			(stroke
				(width 0.1)
				(type default)
			)
			(layer "B.Fab")
		)
		(fp_line
			(start 0.12065 0.2794)
			(end 0.12065 0.3048)
			(stroke
				(width 0.1)
				(type default)
			)
			(layer "B.Fab")
		)
		(fp_line
			(start -0.120396 0.2794)
			(end 0.12065 0.2794)
			(stroke
				(width 0.1)
				(type default)
			)
			(layer "B.Fab")
		)
		(fp_line
			(start 0.67945 0.3048)
			(end 0.67945 -0.305054)
			(stroke
				(width 0.1)
				(type default)
			)
			(layer "B.Fab")
		)
		(fp_line
			(start 0.12065 0.3048)
			(end 0.67945 0.3048)
			(stroke
				(width 0.1)
				(type default)
			)
			(layer "B.Fab")
		)
		(fp_line
			(start -0.120396 0.3048)
			(end -0.120396 0.2794)
			(stroke
				(width 0.1)
				(type default)
			)
			(layer "B.Fab")
		)
		(fp_line
			(start -0.67945 0.3048)
			(end -0.120396 0.3048)
			(stroke
				(width 0.1)
				(type default)
			)
			(layer "B.Fab")
		)
		(pad "1" smd circle
			(at 0.40005 0 270)
			(size 0 0)
			(layers "B.Cu" "B.Mask" "B.Paste")
			(net "SCM_SYS_PWRBTN_N")
		)
		(pad "2" smd circle
			(at -0.40005 0 270)
			(size 0 0)
			(layers "B.Cu" "B.Mask" "B.Paste")
			(net "SCM_SYS_PWRBTN_R_N")
		)
	)
)
